-- pcdb file, Rev:1.0 written by VAN 02.01-s01 on Oct 13, 2005  19:29:25
